(kicad_pcb
	(version 20260206)
	(generator "pcbnew")
	(generator_version "10.0")
	(general
		(thickness 1.6)
		(legacy_teardrops no)
	)
	(paper "A4")
	(title_block
		(title "Bryce Canyon_R.DPB_16317-1_OCP.brd")
		(comment 1 "Bryce Canyon / footprints 846-849 of 2099")
	)
	(layers
		(0 "F.Cu" signal "TOP")
		(4 "In1.Cu" signal "L2GND")
		(6 "In2.Cu" signal "L3")
		(8 "In3.Cu" signal "L4VCC")
		(10 "In4.Cu" signal "L5VCC")
		(12 "In5.Cu" signal "L6")
		(14 "In6.Cu" signal "L7GND")
		(2 "B.Cu" signal "BOTTOM")
		(9 "F.Adhes" user "F.Adhesive")
		(11 "B.Adhes" user "B.Adhesive")
		(13 "F.Paste" user "Package Geometry/Pastemask Top")
		(15 "B.Paste" user "Package Geometry/Pastemask Bottom")
		(5 "F.SilkS" user "Ref Des/Silkscreen Top")
		(7 "B.SilkS" user "Ref Des/Silkscreen Bottom")
		(1 "F.Mask" user "Board Geometry/Soldermask Top")
		(3 "B.Mask" user "Board Geometry/Soldermask Bottom")
		(17 "Dwgs.User" user "User.Drawings")
		(19 "Cmts.User" user "User.Comments")
		(21 "Eco1.User" user "User.Eco1")
		(23 "Eco2.User" user "User.Eco2")
		(25 "Edge.Cuts" user "Board Geometry/Outline")
		(27 "Margin" user)
		(31 "F.CrtYd" user "Package Geometry/Place Bound Top")
		(29 "B.CrtYd" user "Package Geometry/Place Bound Bottom")
		(35 "F.Fab" user "Ref Des/Assembly Top")
		(33 "B.Fab" user "Ref Des/Assembly Bottom")
	)
	(footprint ""
		(layer "F.Cu")
		(at 167.7162 -371.856 90)
		(property "Reference" "R1000"
			(at 0 0 90)
			(layer "F.SilkS")
			(hide yes)
			(effects
				(font
					(size 1.27 1.27)
				)
			)
		)
		(property "Value" "10R2F-L-GP"
			(at 0.064008 -3.993896 90)
			(unlocked yes)
			(layer "F.Fab")
			(hide yes)
			(effects
				(font
					(size 1.016 1.016)
					(thickness 0.1524)
				)
			)
		)
		(property "Device Type" "R402H14"
			(at 0.064008 -5.517896 90)
			(unlocked yes)
			(layer "F.Fab")
			(hide yes)
			(effects
				(font
					(size 1.016 1.016)
					(thickness 0.1524)
				)
			)
		)
		(duplicate_pad_numbers_are_jumpers no)
		(fp_line
			(start 0.508 -0.9398)
			(end -0.508 -0.9398)
			(stroke
				(width 0.1524)
				(type default)
			)
			(layer "F.SilkS")
		)
		(fp_line
			(start -0.508 -0.9398)
			(end -0.508 0.9398)
			(stroke
				(width 0.1524)
				(type default)
			)
			(layer "F.SilkS")
		)
		(fp_rect
			(start -0.508 0.9398)
			(end 0.508 -0.9398)
			(stroke
				(width 0)
				(type default)
			)
			(fill no)
			(layer "F.CrtYd")
		)
		(fp_rect
			(start -0.508 0.9398)
			(end 0.508 -0.9398)
			(stroke
				(width 0)
				(type default)
			)
			(fill no)
			(layer "F.Fab")
		)
		(pad "1" smd custom
			(at 0 -0.4445 90)
			(size 0.1397 0.1397)
			(layers "F.Cu" "F.Mask" "F.Paste")
			(net "MB0_CM_SENSE_R2_N")
			(options
				(clearance outline)
				(anchor circle)
			)
			(primitives
				(gr_poly
					(pts
						(arc
							(start -0.1778 -0.2794)
							(mid -0.249642 -0.249642)
							(end -0.2794 -0.1778)
						)
						(arc
							(start -0.2794 0.1778)
							(mid -0.249642 0.249642)
							(end -0.1778 0.2794)
						)
						(arc
							(start 0.1778 0.2794)
							(mid 0.249642 0.249642)
							(end 0.2794 0.1778)
						)
						(arc
							(start 0.2794 -0.1778)
							(mid 0.249642 -0.249642)
							(end 0.1778 -0.2794)
						)
					)
					(width 0)
					(fill yes)
				)
			)
		)
		(pad "2" smd custom
			(at 0 0.4445 90)
			(size 0.1397 0.1397)
			(layers "F.Cu" "F.Mask" "F.Paste")
			(net "MB0_CM_SENSE_N")
			(options
				(clearance outline)
				(anchor circle)
			)
			(primitives
				(gr_poly
					(pts
						(arc
							(start -0.1778 -0.2794)
							(mid -0.249642 -0.249642)
							(end -0.2794 -0.1778)
						)
						(arc
							(start -0.2794 0.1778)
							(mid -0.249642 0.249642)
							(end -0.1778 0.2794)
						)
						(arc
							(start 0.1778 0.2794)
							(mid 0.249642 0.249642)
							(end 0.2794 0.1778)
						)
						(arc
							(start 0.2794 -0.1778)
							(mid 0.249642 -0.249642)
							(end 0.1778 -0.2794)
						)
					)
					(width 0)
					(fill yes)
				)
			)
		)
	)
	(footprint ""
		(layer "F.Cu")
		(at 458.061568 -97.480628 -90)
		(property "Reference" "R489"
			(at 0 0 270)
			(layer "F.SilkS")
			(hide yes)
			(effects
				(font
					(size 1.27 1.27)
				)
			)
		)
		(property "Value" "4K7R2F-GP"
			(at 0.064008 -3.993896 270)
			(unlocked yes)
			(layer "F.Fab")
			(hide yes)
			(effects
				(font
					(size 1.016 1.016)
					(thickness 0.1524)
				)
			)
		)
		(property "Device Type" "R402H16"
			(at 0.064008 -5.517896 270)
			(unlocked yes)
			(layer "F.Fab")
			(hide yes)
			(effects
				(font
					(size 1.016 1.016)
					(thickness 0.1524)
				)
			)
		)
		(duplicate_pad_numbers_are_jumpers no)
		(fp_line
			(start -0.508 -0.9398)
			(end -0.508 0.9398)
			(stroke
				(width 0.1524)
				(type default)
			)
			(layer "F.SilkS")
		)
		(fp_line
			(start 0.508 -0.9398)
			(end -0.508 -0.9398)
			(stroke
				(width 0.1524)
				(type default)
			)
			(layer "F.SilkS")
		)
		(fp_rect
			(start -0.508 0.9398)
			(end 0.508 -0.9398)
			(stroke
				(width 0)
				(type default)
			)
			(fill no)
			(layer "F.CrtYd")
		)
		(fp_rect
			(start -0.508 0.9398)
			(end 0.508 -0.9398)
			(stroke
				(width 0)
				(type default)
			)
			(fill no)
			(layer "F.Fab")
		)
		(pad "1" smd custom
			(at 0 -0.4445 270)
			(size 0.1397 0.1397)
			(layers "F.Cu" "F.Mask" "F.Paste")
			(net "DRIVE_B_23_ACT")
			(options
				(clearance outline)
				(anchor circle)
			)
			(primitives
				(gr_poly
					(pts
						(arc
							(start -0.1778 -0.2794)
							(mid -0.249642 -0.249642)
							(end -0.2794 -0.1778)
						)
						(arc
							(start -0.2794 0.1778)
							(mid -0.249642 0.249642)
							(end -0.1778 0.2794)
						)
						(arc
							(start 0.1778 0.2794)
							(mid 0.249642 0.249642)
							(end 0.2794 0.1778)
						)
						(arc
							(start 0.2794 -0.1778)
							(mid 0.249642 -0.249642)
							(end 0.1778 -0.2794)
						)
					)
					(width 0)
					(fill yes)
				)
			)
		)
		(pad "2" smd custom
			(at 0 0.4445 270)
			(size 0.1397 0.1397)
			(layers "F.Cu" "F.Mask" "F.Paste")
			(net "GND")
			(options
				(clearance outline)
				(anchor circle)
			)
			(primitives
				(gr_poly
					(pts
						(arc
							(start -0.1778 -0.2794)
							(mid -0.249642 -0.249642)
							(end -0.2794 -0.1778)
						)
						(arc
							(start -0.2794 0.1778)
							(mid -0.249642 0.249642)
							(end -0.1778 0.2794)
						)
						(arc
							(start 0.1778 0.2794)
							(mid 0.249642 0.249642)
							(end 0.2794 0.1778)
						)
						(arc
							(start 0.2794 -0.1778)
							(mid 0.249642 -0.249642)
							(end 0.1778 -0.2794)
						)
					)
					(width 0)
					(fill yes)
				)
			)
		)
	)
	(footprint ""
		(layer "F.Cu")
		(at 222.669862 -205.994 -90)
		(property "Reference" "R47"
			(at 0 0 270)
			(layer "F.SilkS")
			(hide yes)
			(effects
				(font
					(size 1.27 1.27)
				)
			)
		)
		(property "Value" "4K7R2F-GP"
			(at 0.064008 -3.993896 270)
			(unlocked yes)
			(layer "F.Fab")
			(hide yes)
			(effects
				(font
					(size 1.016 1.016)
					(thickness 0.1524)
				)
			)
		)
		(property "Device Type" "R402H16"
			(at 0.064008 -5.517896 270)
			(unlocked yes)
			(layer "F.Fab")
			(hide yes)
			(effects
				(font
					(size 1.016 1.016)
					(thickness 0.1524)
				)
			)
		)
		(duplicate_pad_numbers_are_jumpers no)
		(fp_line
			(start -0.508 -0.9398)
			(end -0.508 0.9398)
			(stroke
				(width 0.1524)
				(type default)
			)
			(layer "F.SilkS")
		)
		(fp_line
			(start 0.508 -0.9398)
			(end -0.508 -0.9398)
			(stroke
				(width 0.1524)
				(type default)
			)
			(layer "F.SilkS")
		)
		(fp_rect
			(start -0.508 0.9398)
			(end 0.508 -0.9398)
			(stroke
				(width 0)
				(type default)
			)
			(fill no)
			(layer "F.CrtYd")
		)
		(fp_rect
			(start -0.508 0.9398)
			(end 0.508 -0.9398)
			(stroke
				(width 0)
				(type default)
			)
			(fill no)
			(layer "F.Fab")
		)
		(pad "1" smd custom
			(at 0 -0.4445 270)
			(size 0.1397 0.1397)
			(layers "F.Cu" "F.Mask" "F.Paste")
			(net "P3V3_STBY_B")
			(options
				(clearance outline)
				(anchor circle)
			)
			(primitives
				(gr_poly
					(pts
						(arc
							(start -0.1778 -0.2794)
							(mid -0.249642 -0.249642)
							(end -0.2794 -0.1778)
						)
						(arc
							(start -0.2794 0.1778)
							(mid -0.249642 0.249642)
							(end -0.1778 0.2794)
						)
						(arc
							(start 0.1778 0.2794)
							(mid 0.249642 0.249642)
							(end 0.2794 0.1778)
						)
						(arc
							(start 0.2794 -0.1778)
							(mid 0.249642 -0.249642)
							(end 0.1778 -0.2794)
						)
					)
					(width 0)
					(fill yes)
				)
			)
		)
		(pad "2" smd custom
			(at 0 0.4445 270)
			(size 0.1397 0.1397)
			(layers "F.Cu" "F.Mask" "F.Paste")
			(net "IO_EXP5_A2")
			(options
				(clearance outline)
				(anchor circle)
			)
			(primitives
				(gr_poly
					(pts
						(arc
							(start -0.1778 -0.2794)
							(mid -0.249642 -0.249642)
							(end -0.2794 -0.1778)
						)
						(arc
							(start -0.2794 0.1778)
							(mid -0.249642 0.249642)
							(end -0.1778 0.2794)
						)
						(arc
							(start 0.1778 0.2794)
							(mid 0.249642 0.249642)
							(end 0.2794 0.1778)
						)
						(arc
							(start 0.2794 -0.1778)
							(mid 0.249642 -0.249642)
							(end 0.1778 -0.2794)
						)
					)
					(width 0)
					(fill yes)
				)
			)
		)
	)
	(footprint ""
		(layer "F.Cu")
		(at 117.602 -249.555 90)
		(property "Reference" "R215"
			(at 0 0 90)
			(layer "F.SilkS")
			(hide yes)
			(effects
				(font
					(size 1.27 1.27)
				)
			)
		)
		(property "Value" "4K7R2F-GP"
			(at 0.064008 -3.993896 90)
			(unlocked yes)
			(layer "F.Fab")
			(hide yes)
			(effects
				(font
					(size 1.016 1.016)
					(thickness 0.1524)
				)
			)
		)
		(property "Device Type" "R402H16"
			(at 0.064008 -5.517896 90)
			(unlocked yes)
			(layer "F.Fab")
			(hide yes)
			(effects
				(font
					(size 1.016 1.016)
					(thickness 0.1524)
				)
			)
		)
		(duplicate_pad_numbers_are_jumpers no)
		(fp_line
			(start 0.508 -0.9398)
			(end -0.508 -0.9398)
			(stroke
				(width 0.1524)
				(type default)
			)
			(layer "F.SilkS")
		)
		(fp_line
			(start -0.508 -0.9398)
			(end -0.508 0.9398)
			(stroke
				(width 0.1524)
				(type default)
			)
			(layer "F.SilkS")
		)
		(fp_rect
			(start -0.508 0.9398)
			(end 0.508 -0.9398)
			(stroke
				(width 0)
				(type default)
			)
			(fill no)
			(layer "F.CrtYd")
		)
		(fp_rect
			(start -0.508 0.9398)
			(end 0.508 -0.9398)
			(stroke
				(width 0)
				(type default)
			)
			(fill no)
			(layer "F.Fab")
		)
		(pad "1" smd custom
			(at 0 -0.4445 90)
			(size 0.1397 0.1397)
			(layers "F.Cu" "F.Mask" "F.Paste")
			(net "SW_PWR_R_HDD3")
			(options
				(clearance outline)
				(anchor circle)
			)
			(primitives
				(gr_poly
					(pts
						(arc
							(start -0.1778 -0.2794)
							(mid -0.249642 -0.249642)
							(end -0.2794 -0.1778)
						)
						(arc
							(start -0.2794 0.1778)
							(mid -0.249642 0.249642)
							(end -0.1778 0.2794)
						)
						(arc
							(start 0.1778 0.2794)
							(mid 0.249642 0.249642)
							(end 0.2794 0.1778)
						)
						(arc
							(start 0.2794 -0.1778)
							(mid 0.249642 -0.249642)
							(end 0.1778 -0.2794)
						)
					)
					(width 0)
					(fill yes)
				)
			)
		)
		(pad "2" smd custom
			(at 0 0.4445 90)
			(size 0.1397 0.1397)
			(layers "F.Cu" "F.Mask" "F.Paste")
			(net "GND")
			(options
				(clearance outline)
				(anchor circle)
			)
			(primitives
				(gr_poly
					(pts
						(arc
							(start -0.1778 -0.2794)
							(mid -0.249642 -0.249642)
							(end -0.2794 -0.1778)
						)
						(arc
							(start -0.2794 0.1778)
							(mid -0.249642 0.249642)
							(end -0.1778 0.2794)
						)
						(arc
							(start 0.1778 0.2794)
							(mid 0.249642 0.249642)
							(end 0.2794 0.1778)
						)
						(arc
							(start 0.2794 -0.1778)
							(mid 0.249642 -0.249642)
							(end 0.1778 -0.2794)
						)
					)
					(width 0)
					(fill yes)
				)
			)
		)
	)
)
